FILE_TYPE = MACRO_DRAWING;
SET COLOR_WIRE YELLOW;
SET COLOR_PROP ORANGE;
SET COLOR_DOT WHITE;
SET COLOR_ARC YELLOW;
SET COLOR_BODY GREEN;
SET COLOR_NOTE PURPLE;
SET PROP_DISPLAY VALUE;
SET PAGE_NUMBER P406;
FORCEADD PT5161LRS..1
(-7875 4150);
FORCEPROP 1 LAST LOCATION U6011
J 0
(-8225 5775);
DISPLAY 0.723404 (-8225 5775);
PAINT GREEN (-8225 5775);
FORCEPROP 0 LAST $SEC 1
J 0
(-8225 5925);
DISPLAY 0.680851 (-8225 5925);
PAINT MONO (-8225 5925);
DISPLAY INVISIBLE (-8225 5925);
FORCEPROP 0 LAST CDS_SEC 1
J 0
(-8225 5925);
DISPLAY 0.680851 (-8225 5925);
DISPLAY INVISIBLE (-8225 5925);
FORCEPROP 0 LASTPIN (-7425 5300) $PN N2
J 0
(-7415 5310);
DISPLAY 0.680851 (-7415 5310);
PAINT MONO (-7415 5310);
FORCEPROP 0 LASTPIN (-7425 4950) $PN Y2
J 0
(-7415 4960);
DISPLAY 0.680851 (-7415 4960);
PAINT MONO (-7415 4960);
FORCEPROP 0 LASTPIN (-7425 4600) $PN AG2
J 0
(-7415 4610);
DISPLAY 0.680851 (-7415 4610);
PAINT MONO (-7415 4610);
FORCEPROP 0 LASTPIN (-7425 4250) $PN AP2
J 0
(-7415 4260);
DISPLAY 0.680851 (-7415 4260);
PAINT MONO (-7415 4260);
FORCEPROP 0 LASTPIN (-7425 3900) $PN BA2
J 0
(-7415 3910);
DISPLAY 0.680851 (-7415 3910);
PAINT MONO (-7415 3910);
FORCEPROP 0 LASTPIN (-7425 3550) $PN BH2
J 0
(-7415 3560);
DISPLAY 0.680851 (-7415 3560);
PAINT MONO (-7415 3560);
FORCEPROP 0 LASTPIN (-7425 3200) $PN BR2
J 0
(-7415 3210);
DISPLAY 0.680851 (-7415 3210);
PAINT MONO (-7415 3210);
FORCEPROP 0 LASTPIN (-7425 2850) $PN CB2
J 0
(-7415 2860);
DISPLAY 0.680851 (-7415 2860);
PAINT MONO (-7415 2860);
FORCEPROP 0 LASTPIN (-7425 5400) $PN R1
J 0
(-7415 5410);
DISPLAY 0.680851 (-7415 5410);
PAINT MONO (-7415 5410);
FORCEPROP 0 LASTPIN (-7425 5050) $PN AB1
J 0
(-7415 5060);
DISPLAY 0.680851 (-7415 5060);
PAINT MONO (-7415 5060);
FORCEPROP 0 LASTPIN (-7425 4700) $PN AJ1
J 0
(-7415 4710);
DISPLAY 0.680851 (-7415 4710);
PAINT MONO (-7415 4710);
FORCEPROP 0 LASTPIN (-7425 4350) $PN AT1
J 0
(-7415 4360);
DISPLAY 0.680851 (-7415 4360);
PAINT MONO (-7415 4360);
FORCEPROP 0 LASTPIN (-7425 4000) $PN BC1
J 0
(-7415 4010);
DISPLAY 0.680851 (-7415 4010);
PAINT MONO (-7415 4010);
FORCEPROP 0 LASTPIN (-7425 3650) $PN BK1
J 0
(-7415 3660);
DISPLAY 0.680851 (-7415 3660);
PAINT MONO (-7415 3660);
FORCEPROP 0 LASTPIN (-7425 3300) $PN BU1
J 0
(-7415 3310);
DISPLAY 0.680851 (-7415 3310);
PAINT MONO (-7415 3310);
FORCEPROP 0 LASTPIN (-7425 2950) $PN CD1
J 0
(-7415 2960);
DISPLAY 0.680851 (-7415 2960);
PAINT MONO (-7415 2960);
FORCEPROP 2 LAST VALUE PT5161LRS
J 0
(-8225 5825);
DISPLAY 0.680851 (-8225 5825);
FORCEPROP 2 LAST PART_TYPE SMLF
J 0
(-8225 5875);
DISPLAY 0.680851 (-8225 5875);
FORCEPROP 1 LAST MATERIAL IC
J 0
(-8225 5625);
DISPLAY 0.723404 (-8225 5625);
PAINT GREEN (-8225 5625);
FORCEPROP 1 LAST NEEDS_NO_SIZE TRUE
J 0
(-7875 4150);
DISPLAY 0.723404 (-7875 4150);
PAINT GREEN (-7875 4150);
DISPLAY INVISIBLE (-7875 4150);
FORCEPROP 1 LAST CDS_LMAN_SYM_OUTLINE -350,1450,300,-1400
J 0
(-7875 4150);
DISPLAY 0.468085 (-7875 4150);
PAINT GREEN (-7875 4150);
DISPLAY INVISIBLE (-7875 4150);
FORCEPROP 2 LAST CDS_LIB pure_quanta
J 0
(-7875 4150);
DISPLAY INVISIBLE (-7875 4150);
FORCEPROP 1 LAST PATH I1
J 0
(-7875 4150);
DISPLAY 0.723404 (-7875 4150);
PAINT GREEN (-7875 4150);
DISPLAY INVISIBLE (-7875 4150);
FORCEPROP 1 LAST PART_NUMBER AJ051610U03
J 0
(-8225 5700);
DISPLAY 0.723404 (-8225 5700);
PAINT GREEN (-8225 5700);
DISPLAY INVISIBLE (-8225 5700);
FORCEADD TAP..1
(-6650 4250);
FORCEPROP 3 LASTPIN (-6700 4250) SIG_NAME P5E_CPU0_P1_RX_BUF_DN<12>
J 0
(-6690 4260);
DISPLAY 0.659574 (-6690 4260);
PAINT MONO (-6690 4260);
DISPLAY INVISIBLE (-6690 4260);
FORCEPROP 1 LASTPIN (-6700 4250) BN 12
J 0
(-6712 4258);
DISPLAY 0.680851 (-6712 4258);
PAINT GREEN (-6712 4258);
FORCEPROP 2 LAST CDS_LIB standard
J 0
(-6650 4250);
DISPLAY INVISIBLE (-6650 4250);
FORCEPROP 1 LAST BODY_TYPE PLUMBING
J 0
(-6650 4300);
DISPLAY 0.872340 (-6650 4300);
PAINT GREEN (-6650 4300);
DISPLAY INVISIBLE (-6650 4300);
FORCEPROP 1 LAST HDL_TAP TRUE
J 0
(-6325 4125);
DISPLAY 0.872340 (-6325 4125);
DISPLAY INVISIBLE (-6325 4125);
FORCEPROP 1 LAST PATH I10
J 0
(-6652 4250);
DISPLAY 0.872340 (-6652 4250);
PAINT GREEN (-6652 4250);
DISPLAY INVISIBLE (-6652 4250);
FORCEADD TAP..1
(-6850 4350);
FORCEPROP 3 LASTPIN (-6900 4350) SIG_NAME P5E_CPU0_P1_RX_BUF_DP<12>
J 0
(-6890 4360);
DISPLAY 0.659574 (-6890 4360);
PAINT MONO (-6890 4360);
DISPLAY INVISIBLE (-6890 4360);
FORCEPROP 1 LASTPIN (-6900 4350) BN 12
J 0
(-6912 4358);
DISPLAY 0.680851 (-6912 4358);
PAINT GREEN (-6912 4358);
FORCEPROP 2 LAST CDS_LIB standard
J 0
(-6850 4350);
DISPLAY INVISIBLE (-6850 4350);
FORCEPROP 1 LAST BODY_TYPE PLUMBING
J 0
(-6850 4400);
DISPLAY 0.872340 (-6850 4400);
PAINT GREEN (-6850 4400);
DISPLAY INVISIBLE (-6850 4400);
FORCEPROP 1 LAST HDL_TAP TRUE
J 0
(-6525 4225);
DISPLAY 0.872340 (-6525 4225);
DISPLAY INVISIBLE (-6525 4225);
FORCEPROP 1 LAST PATH I11
J 0
(-6852 4350);
DISPLAY 0.872340 (-6852 4350);
PAINT GREEN (-6852 4350);
DISPLAY INVISIBLE (-6852 4350);
FORCEADD TAP..1
(-6650 4600);
FORCEPROP 3 LASTPIN (-6700 4600) SIG_NAME P5E_CPU0_P1_RX_BUF_DN<13>
J 0
(-6690 4610);
DISPLAY 0.659574 (-6690 4610);
PAINT MONO (-6690 4610);
DISPLAY INVISIBLE (-6690 4610);
FORCEPROP 1 LASTPIN (-6700 4600) BN 13
J 0
(-6712 4608);
DISPLAY 0.680851 (-6712 4608);
PAINT GREEN (-6712 4608);
FORCEPROP 2 LAST CDS_LIB standard
J 0
(-6650 4600);
DISPLAY INVISIBLE (-6650 4600);
FORCEPROP 1 LAST BODY_TYPE PLUMBING
J 0
(-6650 4650);
DISPLAY 0.872340 (-6650 4650);
PAINT GREEN (-6650 4650);
DISPLAY INVISIBLE (-6650 4650);
FORCEPROP 1 LAST HDL_TAP TRUE
J 0
(-6325 4475);
DISPLAY 0.872340 (-6325 4475);
DISPLAY INVISIBLE (-6325 4475);
FORCEPROP 1 LAST PATH I12
J 0
(-6652 4600);
DISPLAY 0.872340 (-6652 4600);
PAINT GREEN (-6652 4600);
DISPLAY INVISIBLE (-6652 4600);
FORCEADD TAP..1
(-6850 4700);
FORCEPROP 3 LASTPIN (-6900 4700) SIG_NAME P5E_CPU0_P1_RX_BUF_DP<13>
J 0
(-6890 4710);
DISPLAY 0.659574 (-6890 4710);
PAINT MONO (-6890 4710);
DISPLAY INVISIBLE (-6890 4710);
FORCEPROP 1 LASTPIN (-6900 4700) BN 13
J 0
(-6912 4708);
DISPLAY 0.680851 (-6912 4708);
PAINT GREEN (-6912 4708);
FORCEPROP 2 LAST CDS_LIB standard
J 0
(-6850 4700);
DISPLAY INVISIBLE (-6850 4700);
FORCEPROP 1 LAST BODY_TYPE PLUMBING
J 0
(-6850 4750);
DISPLAY 0.872340 (-6850 4750);
PAINT GREEN (-6850 4750);
DISPLAY INVISIBLE (-6850 4750);
FORCEPROP 1 LAST HDL_TAP TRUE
J 0
(-6525 4575);
DISPLAY 0.872340 (-6525 4575);
DISPLAY INVISIBLE (-6525 4575);
FORCEPROP 1 LAST PATH I13
J 0
(-6852 4700);
DISPLAY 0.872340 (-6852 4700);
PAINT GREEN (-6852 4700);
DISPLAY INVISIBLE (-6852 4700);
FORCEADD TAP..1
(-6650 4950);
FORCEPROP 3 LASTPIN (-6700 4950) SIG_NAME P5E_CPU0_P1_RX_BUF_DN<14>
J 0
(-6690 4960);
DISPLAY 0.659574 (-6690 4960);
PAINT MONO (-6690 4960);
DISPLAY INVISIBLE (-6690 4960);
FORCEPROP 1 LASTPIN (-6700 4950) BN 14
J 0
(-6712 4958);
DISPLAY 0.680851 (-6712 4958);
PAINT GREEN (-6712 4958);
FORCEPROP 2 LAST CDS_LIB standard
J 0
(-6650 4950);
DISPLAY INVISIBLE (-6650 4950);
FORCEPROP 1 LAST BODY_TYPE PLUMBING
J 0
(-6650 5000);
DISPLAY 0.872340 (-6650 5000);
PAINT GREEN (-6650 5000);
DISPLAY INVISIBLE (-6650 5000);
FORCEPROP 1 LAST HDL_TAP TRUE
J 0
(-6325 4825);
DISPLAY 0.872340 (-6325 4825);
DISPLAY INVISIBLE (-6325 4825);
FORCEPROP 1 LAST PATH I14
J 0
(-6652 4950);
DISPLAY 0.872340 (-6652 4950);
PAINT GREEN (-6652 4950);
DISPLAY INVISIBLE (-6652 4950);
FORCEADD TAP..1
(-6850 5050);
FORCEPROP 3 LASTPIN (-6900 5050) SIG_NAME P5E_CPU0_P1_RX_BUF_DP<14>
J 0
(-6890 5060);
DISPLAY 0.659574 (-6890 5060);
PAINT MONO (-6890 5060);
DISPLAY INVISIBLE (-6890 5060);
FORCEPROP 1 LASTPIN (-6900 5050) BN 14
J 0
(-6912 5058);
DISPLAY 0.680851 (-6912 5058);
PAINT GREEN (-6912 5058);
FORCEPROP 2 LAST CDS_LIB standard
J 0
(-6850 5050);
DISPLAY INVISIBLE (-6850 5050);
FORCEPROP 1 LAST BODY_TYPE PLUMBING
J 0
(-6850 5100);
DISPLAY 0.872340 (-6850 5100);
PAINT GREEN (-6850 5100);
DISPLAY INVISIBLE (-6850 5100);
FORCEPROP 1 LAST HDL_TAP TRUE
J 0
(-6525 4925);
DISPLAY 0.872340 (-6525 4925);
DISPLAY INVISIBLE (-6525 4925);
FORCEPROP 1 LAST PATH I15
J 0
(-6852 5050);
DISPLAY 0.872340 (-6852 5050);
PAINT GREEN (-6852 5050);
DISPLAY INVISIBLE (-6852 5050);
FORCEADD TAP..1
(-6850 5400);
FORCEPROP 3 LASTPIN (-6900 5400) SIG_NAME P5E_CPU0_P1_RX_BUF_DP<15>
J 0
(-6890 5410);
DISPLAY 0.659574 (-6890 5410);
PAINT MONO (-6890 5410);
DISPLAY INVISIBLE (-6890 5410);
FORCEPROP 1 LASTPIN (-6900 5400) BN 15
J 0
(-6912 5408);
DISPLAY 0.680851 (-6912 5408);
PAINT GREEN (-6912 5408);
FORCEPROP 2 LAST CDS_LIB standard
J 0
(-6850 5400);
DISPLAY INVISIBLE (-6850 5400);
FORCEPROP 1 LAST BODY_TYPE PLUMBING
J 0
(-6850 5450);
DISPLAY 0.872340 (-6850 5450);
PAINT GREEN (-6850 5450);
DISPLAY INVISIBLE (-6850 5450);
FORCEPROP 1 LAST HDL_TAP TRUE
J 0
(-6525 5275);
DISPLAY 0.872340 (-6525 5275);
DISPLAY INVISIBLE (-6525 5275);
FORCEPROP 1 LAST PATH I16
J 0
(-6852 5400);
DISPLAY 0.872340 (-6852 5400);
PAINT GREEN (-6852 5400);
DISPLAY INVISIBLE (-6852 5400);
FORCEADD TAP..1
(-6650 5300);
FORCEPROP 3 LASTPIN (-6700 5300) SIG_NAME P5E_CPU0_P1_RX_BUF_DN<15>
J 0
(-6690 5310);
DISPLAY 0.659574 (-6690 5310);
PAINT MONO (-6690 5310);
DISPLAY INVISIBLE (-6690 5310);
FORCEPROP 1 LASTPIN (-6700 5300) BN 15
J 0
(-6712 5308);
DISPLAY 0.680851 (-6712 5308);
PAINT GREEN (-6712 5308);
FORCEPROP 2 LAST CDS_LIB standard
J 0
(-6650 5300);
DISPLAY INVISIBLE (-6650 5300);
FORCEPROP 1 LAST BODY_TYPE PLUMBING
J 0
(-6650 5350);
DISPLAY 0.872340 (-6650 5350);
PAINT GREEN (-6650 5350);
DISPLAY INVISIBLE (-6650 5350);
FORCEPROP 1 LAST HDL_TAP TRUE
J 0
(-6325 5175);
DISPLAY 0.872340 (-6325 5175);
DISPLAY INVISIBLE (-6325 5175);
FORCEPROP 1 LAST PATH I17
J 0
(-6652 5300);
DISPLAY 0.872340 (-6652 5300);
PAINT GREEN (-6652 5300);
DISPLAY INVISIBLE (-6652 5300);
FORCEADD OFFPAGE..1
R 2
(-5625 5425);
FORCEPROP 2 LAST $XR0 117 
J 0
(-5439 5425);
DISPLAY 0.638298 (-5439 5425);
PAINT MONO (-5439 5425);
FORCEPROP 2 LAST CDS_LIB standard
J 0
(-5625 5425);
DISPLAY INVISIBLE (-5625 5425);
FORCEPROP 1 LAST OFFPAGE TRUE
J 2
(-5950 5300);
DISPLAY 0.872340 (-5950 5300);
DISPLAY INVISIBLE (-5950 5300);
FORCEPROP 1 LAST COMMENT_BODY TRUE
J 2
(-5750 5325);
DISPLAY 0.872340 (-5750 5325);
PAINT GREEN (-5750 5325);
DISPLAY INVISIBLE (-5750 5325);
FORCEPROP 2 LAST PATH I18
J 0
(-5450 5500);
DISPLAY 0.680851 (-5450 5500);
DISPLAY INVISIBLE (-5450 5500);
FORCEADD OFFPAGE..1
R 2
(-5625 5500);
FORCEPROP 2 LAST $XR0 117 
J 0
(-5439 5500);
DISPLAY 0.638298 (-5439 5500);
PAINT MONO (-5439 5500);
FORCEPROP 2 LAST CDS_LIB standard
J 0
(-5625 5500);
DISPLAY INVISIBLE (-5625 5500);
FORCEPROP 1 LAST OFFPAGE TRUE
J 2
(-5950 5375);
DISPLAY 0.872340 (-5950 5375);
DISPLAY INVISIBLE (-5950 5375);
FORCEPROP 1 LAST COMMENT_BODY TRUE
J 2
(-5750 5400);
DISPLAY 0.872340 (-5750 5400);
PAINT GREEN (-5750 5400);
DISPLAY INVISIBLE (-5750 5400);
FORCEPROP 2 LAST PATH I19
J 0
(-5450 5575);
DISPLAY 0.680851 (-5450 5575);
DISPLAY INVISIBLE (-5450 5575);
FORCEADD TAP..1
(-6850 2950);
FORCEPROP 3 LASTPIN (-6900 2950) SIG_NAME P5E_CPU0_P1_RX_BUF_DP<8>
J 0
(-6890 2960);
DISPLAY 0.659574 (-6890 2960);
PAINT MONO (-6890 2960);
DISPLAY INVISIBLE (-6890 2960);
FORCEPROP 1 LASTPIN (-6900 2950) BN 8
J 0
(-6912 2958);
DISPLAY 0.680851 (-6912 2958);
PAINT GREEN (-6912 2958);
FORCEPROP 2 LAST CDS_LIB standard
J 0
(-6850 2950);
DISPLAY INVISIBLE (-6850 2950);
FORCEPROP 1 LAST BODY_TYPE PLUMBING
J 0
(-6850 3000);
DISPLAY 0.872340 (-6850 3000);
PAINT GREEN (-6850 3000);
DISPLAY INVISIBLE (-6850 3000);
FORCEPROP 1 LAST HDL_TAP TRUE
J 0
(-6525 2825);
DISPLAY 0.872340 (-6525 2825);
DISPLAY INVISIBLE (-6525 2825);
FORCEPROP 1 LAST PATH I2
J 0
(-6852 2950);
DISPLAY 0.872340 (-6852 2950);
PAINT GREEN (-6852 2950);
DISPLAY INVISIBLE (-6852 2950);
FORCEADD TAP..1
(-2400 2975);
FORCEPROP 3 LASTPIN (-2450 2975) SIG_NAME P5E_CPU0_P1_RX_BUF_DP<0>
J 0
(-2440 2985);
DISPLAY 0.659574 (-2440 2985);
PAINT MONO (-2440 2985);
DISPLAY INVISIBLE (-2440 2985);
FORCEPROP 1 LASTPIN (-2450 2975) BN 0
J 0
(-2462 2983);
DISPLAY 0.680851 (-2462 2983);
PAINT GREEN (-2462 2983);
FORCEPROP 2 LAST CDS_LIB standard
J 0
(-2400 2975);
DISPLAY INVISIBLE (-2400 2975);
FORCEPROP 1 LAST BODY_TYPE PLUMBING
J 0
(-2400 3025);
DISPLAY 0.872340 (-2400 3025);
PAINT GREEN (-2400 3025);
DISPLAY INVISIBLE (-2400 3025);
FORCEPROP 1 LAST HDL_TAP TRUE
J 0
(-2075 2850);
DISPLAY 0.872340 (-2075 2850);
DISPLAY INVISIBLE (-2075 2850);
FORCEPROP 1 LAST PATH I20
J 0
(-2402 2975);
DISPLAY 0.872340 (-2402 2975);
PAINT GREEN (-2402 2975);
DISPLAY INVISIBLE (-2402 2975);
FORCEADD TAP..1
(-2200 2875);
FORCEPROP 3 LASTPIN (-2250 2875) SIG_NAME P5E_CPU0_P1_RX_BUF_DN<0>
J 0
(-2240 2885);
DISPLAY 0.659574 (-2240 2885);
PAINT MONO (-2240 2885);
DISPLAY INVISIBLE (-2240 2885);
FORCEPROP 1 LASTPIN (-2250 2875) BN 0
J 0
(-2262 2883);
DISPLAY 0.680851 (-2262 2883);
PAINT GREEN (-2262 2883);
FORCEPROP 2 LAST CDS_LIB standard
J 0
(-2200 2875);
DISPLAY INVISIBLE (-2200 2875);
FORCEPROP 1 LAST BODY_TYPE PLUMBING
J 0
(-2200 2925);
DISPLAY 0.872340 (-2200 2925);
PAINT GREEN (-2200 2925);
DISPLAY INVISIBLE (-2200 2925);
FORCEPROP 1 LAST HDL_TAP TRUE
J 0
(-1875 2750);
DISPLAY 0.872340 (-1875 2750);
DISPLAY INVISIBLE (-1875 2750);
FORCEPROP 1 LAST PATH I21
J 0
(-2202 2875);
DISPLAY 0.872340 (-2202 2875);
PAINT GREEN (-2202 2875);
DISPLAY INVISIBLE (-2202 2875);
FORCEADD TAP..1
(-2400 3325);
FORCEPROP 3 LASTPIN (-2450 3325) SIG_NAME P5E_CPU0_P1_RX_BUF_DP<1>
J 0
(-2440 3335);
DISPLAY 0.659574 (-2440 3335);
PAINT MONO (-2440 3335);
DISPLAY INVISIBLE (-2440 3335);
FORCEPROP 1 LASTPIN (-2450 3325) BN 1
J 0
(-2462 3333);
DISPLAY 0.680851 (-2462 3333);
PAINT GREEN (-2462 3333);
FORCEPROP 2 LAST CDS_LIB standard
J 0
(-2400 3325);
DISPLAY INVISIBLE (-2400 3325);
FORCEPROP 1 LAST BODY_TYPE PLUMBING
J 0
(-2400 3375);
DISPLAY 0.872340 (-2400 3375);
PAINT GREEN (-2400 3375);
DISPLAY INVISIBLE (-2400 3375);
FORCEPROP 1 LAST HDL_TAP TRUE
J 0
(-2075 3200);
DISPLAY 0.872340 (-2075 3200);
DISPLAY INVISIBLE (-2075 3200);
FORCEPROP 1 LAST PATH I22
J 0
(-2402 3325);
DISPLAY 0.872340 (-2402 3325);
PAINT GREEN (-2402 3325);
DISPLAY INVISIBLE (-2402 3325);
FORCEADD TAP..1
(-2400 3675);
FORCEPROP 3 LASTPIN (-2450 3675) SIG_NAME P5E_CPU0_P1_RX_BUF_DP<2>
J 0
(-2440 3685);
DISPLAY 0.659574 (-2440 3685);
PAINT MONO (-2440 3685);
DISPLAY INVISIBLE (-2440 3685);
FORCEPROP 1 LASTPIN (-2450 3675) BN 2
J 0
(-2462 3683);
DISPLAY 0.680851 (-2462 3683);
PAINT GREEN (-2462 3683);
FORCEPROP 2 LAST CDS_LIB standard
J 0
(-2400 3675);
DISPLAY INVISIBLE (-2400 3675);
FORCEPROP 1 LAST BODY_TYPE PLUMBING
J 0
(-2400 3725);
DISPLAY 0.872340 (-2400 3725);
PAINT GREEN (-2400 3725);
DISPLAY INVISIBLE (-2400 3725);
FORCEPROP 1 LAST HDL_TAP TRUE
J 0
(-2075 3550);
DISPLAY 0.872340 (-2075 3550);
DISPLAY INVISIBLE (-2075 3550);
FORCEPROP 1 LAST PATH I23
J 0
(-2402 3675);
DISPLAY 0.872340 (-2402 3675);
PAINT GREEN (-2402 3675);
DISPLAY INVISIBLE (-2402 3675);
FORCEADD TAP..1
(-2400 4025);
FORCEPROP 3 LASTPIN (-2450 4025) SIG_NAME P5E_CPU0_P1_RX_BUF_DP<3>
J 0
(-2440 4035);
DISPLAY 0.659574 (-2440 4035);
PAINT MONO (-2440 4035);
DISPLAY INVISIBLE (-2440 4035);
FORCEPROP 1 LASTPIN (-2450 4025) BN 3
J 0
(-2462 4033);
DISPLAY 0.680851 (-2462 4033);
PAINT GREEN (-2462 4033);
FORCEPROP 2 LAST CDS_LIB standard
J 0
(-2400 4025);
DISPLAY INVISIBLE (-2400 4025);
FORCEPROP 1 LAST BODY_TYPE PLUMBING
J 0
(-2400 4075);
DISPLAY 0.872340 (-2400 4075);
PAINT GREEN (-2400 4075);
DISPLAY INVISIBLE (-2400 4075);
FORCEPROP 1 LAST HDL_TAP TRUE
J 0
(-2075 3900);
DISPLAY 0.872340 (-2075 3900);
DISPLAY INVISIBLE (-2075 3900);
FORCEPROP 1 LAST PATH I24
J 0
(-2402 4025);
DISPLAY 0.872340 (-2402 4025);
PAINT GREEN (-2402 4025);
DISPLAY INVISIBLE (-2402 4025);
FORCEADD TAP..1
(-2200 3225);
FORCEPROP 3 LASTPIN (-2250 3225) SIG_NAME P5E_CPU0_P1_RX_BUF_DN<1>
J 0
(-2240 3235);
DISPLAY 0.659574 (-2240 3235);
PAINT MONO (-2240 3235);
DISPLAY INVISIBLE (-2240 3235);
FORCEPROP 1 LASTPIN (-2250 3225) BN 1
J 0
(-2262 3233);
DISPLAY 0.680851 (-2262 3233);
PAINT GREEN (-2262 3233);
FORCEPROP 2 LAST CDS_LIB standard
J 0
(-2200 3225);
DISPLAY INVISIBLE (-2200 3225);
FORCEPROP 1 LAST BODY_TYPE PLUMBING
J 0
(-2200 3275);
DISPLAY 0.872340 (-2200 3275);
PAINT GREEN (-2200 3275);
DISPLAY INVISIBLE (-2200 3275);
FORCEPROP 1 LAST HDL_TAP TRUE
J 0
(-1875 3100);
DISPLAY 0.872340 (-1875 3100);
DISPLAY INVISIBLE (-1875 3100);
FORCEPROP 1 LAST PATH I25
J 0
(-2202 3225);
DISPLAY 0.872340 (-2202 3225);
PAINT GREEN (-2202 3225);
DISPLAY INVISIBLE (-2202 3225);
FORCEADD TAP..1
(-2200 3575);
FORCEPROP 3 LASTPIN (-2250 3575) SIG_NAME P5E_CPU0_P1_RX_BUF_DN<2>
J 0
(-2240 3585);
DISPLAY 0.659574 (-2240 3585);
PAINT MONO (-2240 3585);
DISPLAY INVISIBLE (-2240 3585);
FORCEPROP 1 LASTPIN (-2250 3575) BN 2
J 0
(-2262 3583);
DISPLAY 0.680851 (-2262 3583);
PAINT GREEN (-2262 3583);
FORCEPROP 2 LAST CDS_LIB standard
J 0
(-2200 3575);
DISPLAY INVISIBLE (-2200 3575);
FORCEPROP 1 LAST BODY_TYPE PLUMBING
J 0
(-2200 3625);
DISPLAY 0.872340 (-2200 3625);
PAINT GREEN (-2200 3625);
DISPLAY INVISIBLE (-2200 3625);
FORCEPROP 1 LAST HDL_TAP TRUE
J 0
(-1875 3450);
DISPLAY 0.872340 (-1875 3450);
DISPLAY INVISIBLE (-1875 3450);
FORCEPROP 1 LAST PATH I26
J 0
(-2202 3575);
DISPLAY 0.872340 (-2202 3575);
PAINT GREEN (-2202 3575);
DISPLAY INVISIBLE (-2202 3575);
FORCEADD TAP..1
(-2200 3925);
FORCEPROP 3 LASTPIN (-2250 3925) SIG_NAME P5E_CPU0_P1_RX_BUF_DN<3>
J 0
(-2240 3935);
DISPLAY 0.659574 (-2240 3935);
PAINT MONO (-2240 3935);
DISPLAY INVISIBLE (-2240 3935);
FORCEPROP 1 LASTPIN (-2250 3925) BN 3
J 0
(-2262 3933);
DISPLAY 0.680851 (-2262 3933);
PAINT GREEN (-2262 3933);
FORCEPROP 2 LAST CDS_LIB standard
J 0
(-2200 3925);
DISPLAY INVISIBLE (-2200 3925);
FORCEPROP 1 LAST BODY_TYPE PLUMBING
J 0
(-2200 3975);
DISPLAY 0.872340 (-2200 3975);
PAINT GREEN (-2200 3975);
DISPLAY INVISIBLE (-2200 3975);
FORCEPROP 1 LAST HDL_TAP TRUE
J 0
(-1875 3800);
DISPLAY 0.872340 (-1875 3800);
DISPLAY INVISIBLE (-1875 3800);
FORCEPROP 1 LAST PATH I27
J 0
(-2202 3925);
DISPLAY 0.872340 (-2202 3925);
PAINT GREEN (-2202 3925);
DISPLAY INVISIBLE (-2202 3925);
FORCEADD TAP..1
(-2400 4375);
FORCEPROP 3 LASTPIN (-2450 4375) SIG_NAME P5E_CPU0_P1_RX_BUF_DP<4>
J 0
(-2440 4385);
DISPLAY 0.659574 (-2440 4385);
PAINT MONO (-2440 4385);
DISPLAY INVISIBLE (-2440 4385);
FORCEPROP 1 LASTPIN (-2450 4375) BN 4
J 0
(-2462 4383);
DISPLAY 0.680851 (-2462 4383);
PAINT GREEN (-2462 4383);
FORCEPROP 2 LAST CDS_LIB standard
J 0
(-2400 4375);
DISPLAY INVISIBLE (-2400 4375);
FORCEPROP 1 LAST BODY_TYPE PLUMBING
J 0
(-2400 4425);
DISPLAY 0.872340 (-2400 4425);
PAINT GREEN (-2400 4425);
DISPLAY INVISIBLE (-2400 4425);
FORCEPROP 1 LAST HDL_TAP TRUE
J 0
(-2075 4250);
DISPLAY 0.872340 (-2075 4250);
DISPLAY INVISIBLE (-2075 4250);
FORCEPROP 1 LAST PATH I28
J 0
(-2402 4375);
DISPLAY 0.872340 (-2402 4375);
PAINT GREEN (-2402 4375);
DISPLAY INVISIBLE (-2402 4375);
FORCEADD TAP..1
(-2400 4725);
FORCEPROP 3 LASTPIN (-2450 4725) SIG_NAME P5E_CPU0_P1_RX_BUF_DP<5>
J 0
(-2440 4735);
DISPLAY 0.659574 (-2440 4735);
PAINT MONO (-2440 4735);
DISPLAY INVISIBLE (-2440 4735);
FORCEPROP 1 LASTPIN (-2450 4725) BN 5
J 0
(-2462 4733);
DISPLAY 0.680851 (-2462 4733);
PAINT GREEN (-2462 4733);
FORCEPROP 2 LAST CDS_LIB standard
J 0
(-2400 4725);
DISPLAY INVISIBLE (-2400 4725);
FORCEPROP 1 LAST BODY_TYPE PLUMBING
J 0
(-2400 4775);
DISPLAY 0.872340 (-2400 4775);
PAINT GREEN (-2400 4775);
DISPLAY INVISIBLE (-2400 4775);
FORCEPROP 1 LAST HDL_TAP TRUE
J 0
(-2075 4600);
DISPLAY 0.872340 (-2075 4600);
DISPLAY INVISIBLE (-2075 4600);
FORCEPROP 1 LAST PATH I29
J 0
(-2402 4725);
DISPLAY 0.872340 (-2402 4725);
PAINT GREEN (-2402 4725);
DISPLAY INVISIBLE (-2402 4725);
FORCEADD TAP..1
(-6650 2850);
FORCEPROP 3 LASTPIN (-6700 2850) SIG_NAME P5E_CPU0_P1_RX_BUF_DN<8>
J 0
(-6690 2860);
DISPLAY 0.659574 (-6690 2860);
PAINT MONO (-6690 2860);
DISPLAY INVISIBLE (-6690 2860);
FORCEPROP 1 LASTPIN (-6700 2850) BN 8
J 0
(-6712 2858);
DISPLAY 0.680851 (-6712 2858);
PAINT GREEN (-6712 2858);
FORCEPROP 2 LAST CDS_LIB standard
J 0
(-6650 2850);
DISPLAY INVISIBLE (-6650 2850);
FORCEPROP 1 LAST BODY_TYPE PLUMBING
J 0
(-6650 2900);
DISPLAY 0.872340 (-6650 2900);
PAINT GREEN (-6650 2900);
DISPLAY INVISIBLE (-6650 2900);
FORCEPROP 1 LAST HDL_TAP TRUE
J 0
(-6325 2725);
DISPLAY 0.872340 (-6325 2725);
DISPLAY INVISIBLE (-6325 2725);
FORCEPROP 1 LAST PATH I3
J 0
(-6652 2850);
DISPLAY 0.872340 (-6652 2850);
PAINT GREEN (-6652 2850);
DISPLAY INVISIBLE (-6652 2850);
FORCEADD TAP..1
(-2400 5075);
FORCEPROP 3 LASTPIN (-2450 5075) SIG_NAME P5E_CPU0_P1_RX_BUF_DP<6>
J 0
(-2440 5085);
DISPLAY 0.659574 (-2440 5085);
PAINT MONO (-2440 5085);
DISPLAY INVISIBLE (-2440 5085);
FORCEPROP 1 LASTPIN (-2450 5075) BN 6
J 0
(-2462 5083);
DISPLAY 0.680851 (-2462 5083);
PAINT GREEN (-2462 5083);
FORCEPROP 2 LAST CDS_LIB standard
J 0
(-2400 5075);
DISPLAY INVISIBLE (-2400 5075);
FORCEPROP 1 LAST BODY_TYPE PLUMBING
J 0
(-2400 5125);
DISPLAY 0.872340 (-2400 5125);
PAINT GREEN (-2400 5125);
DISPLAY INVISIBLE (-2400 5125);
FORCEPROP 1 LAST HDL_TAP TRUE
J 0
(-2075 4950);
DISPLAY 0.872340 (-2075 4950);
DISPLAY INVISIBLE (-2075 4950);
FORCEPROP 1 LAST PATH I30
J 0
(-2402 5075);
DISPLAY 0.872340 (-2402 5075);
PAINT GREEN (-2402 5075);
DISPLAY INVISIBLE (-2402 5075);
FORCEADD TAP..1
(-2200 4275);
FORCEPROP 3 LASTPIN (-2250 4275) SIG_NAME P5E_CPU0_P1_RX_BUF_DN<4>
J 0
(-2240 4285);
DISPLAY 0.659574 (-2240 4285);
PAINT MONO (-2240 4285);
DISPLAY INVISIBLE (-2240 4285);
FORCEPROP 1 LASTPIN (-2250 4275) BN 4
J 0
(-2262 4283);
DISPLAY 0.680851 (-2262 4283);
PAINT GREEN (-2262 4283);
FORCEPROP 2 LAST CDS_LIB standard
J 0
(-2200 4275);
DISPLAY INVISIBLE (-2200 4275);
FORCEPROP 1 LAST BODY_TYPE PLUMBING
J 0
(-2200 4325);
DISPLAY 0.872340 (-2200 4325);
PAINT GREEN (-2200 4325);
DISPLAY INVISIBLE (-2200 4325);
FORCEPROP 1 LAST HDL_TAP TRUE
J 0
(-1875 4150);
DISPLAY 0.872340 (-1875 4150);
DISPLAY INVISIBLE (-1875 4150);
FORCEPROP 1 LAST PATH I31
J 0
(-2202 4275);
DISPLAY 0.872340 (-2202 4275);
PAINT GREEN (-2202 4275);
DISPLAY INVISIBLE (-2202 4275);
FORCEADD TAP..1
(-2200 4625);
FORCEPROP 3 LASTPIN (-2250 4625) SIG_NAME P5E_CPU0_P1_RX_BUF_DN<5>
J 0
(-2240 4635);
DISPLAY 0.659574 (-2240 4635);
PAINT MONO (-2240 4635);
DISPLAY INVISIBLE (-2240 4635);
FORCEPROP 1 LASTPIN (-2250 4625) BN 5
J 0
(-2262 4633);
DISPLAY 0.680851 (-2262 4633);
PAINT GREEN (-2262 4633);
FORCEPROP 2 LAST CDS_LIB standard
J 0
(-2200 4625);
DISPLAY INVISIBLE (-2200 4625);
FORCEPROP 1 LAST BODY_TYPE PLUMBING
J 0
(-2200 4675);
DISPLAY 0.872340 (-2200 4675);
PAINT GREEN (-2200 4675);
DISPLAY INVISIBLE (-2200 4675);
FORCEPROP 1 LAST HDL_TAP TRUE
J 0
(-1875 4500);
DISPLAY 0.872340 (-1875 4500);
DISPLAY INVISIBLE (-1875 4500);
FORCEPROP 1 LAST PATH I32
J 0
(-2202 4625);
DISPLAY 0.872340 (-2202 4625);
PAINT GREEN (-2202 4625);
DISPLAY INVISIBLE (-2202 4625);
FORCEADD TAP..1
(-2200 4975);
FORCEPROP 3 LASTPIN (-2250 4975) SIG_NAME P5E_CPU0_P1_RX_BUF_DN<6>
J 0
(-2240 4985);
DISPLAY 0.659574 (-2240 4985);
PAINT MONO (-2240 4985);
DISPLAY INVISIBLE (-2240 4985);
FORCEPROP 1 LASTPIN (-2250 4975) BN 6
J 0
(-2262 4983);
DISPLAY 0.680851 (-2262 4983);
PAINT GREEN (-2262 4983);
FORCEPROP 2 LAST CDS_LIB standard
J 0
(-2200 4975);
DISPLAY INVISIBLE (-2200 4975);
FORCEPROP 1 LAST BODY_TYPE PLUMBING
J 0
(-2200 5025);
DISPLAY 0.872340 (-2200 5025);
PAINT GREEN (-2200 5025);
DISPLAY INVISIBLE (-2200 5025);
FORCEPROP 1 LAST HDL_TAP TRUE
J 0
(-1875 4850);
DISPLAY 0.872340 (-1875 4850);
DISPLAY INVISIBLE (-1875 4850);
FORCEPROP 1 LAST PATH I33
J 0
(-2202 4975);
DISPLAY 0.872340 (-2202 4975);
PAINT GREEN (-2202 4975);
DISPLAY INVISIBLE (-2202 4975);
FORCEADD TAP..1
(-2400 5425);
FORCEPROP 3 LASTPIN (-2450 5425) SIG_NAME P5E_CPU0_P1_RX_BUF_DP<7>
J 0
(-2440 5435);
DISPLAY 0.659574 (-2440 5435);
PAINT MONO (-2440 5435);
DISPLAY INVISIBLE (-2440 5435);
FORCEPROP 1 LASTPIN (-2450 5425) BN 7
J 0
(-2462 5433);
DISPLAY 0.680851 (-2462 5433);
PAINT GREEN (-2462 5433);
FORCEPROP 2 LAST CDS_LIB standard
J 0
(-2400 5425);
DISPLAY INVISIBLE (-2400 5425);
FORCEPROP 1 LAST BODY_TYPE PLUMBING
J 0
(-2400 5475);
DISPLAY 0.872340 (-2400 5475);
PAINT GREEN (-2400 5475);
DISPLAY INVISIBLE (-2400 5475);
FORCEPROP 1 LAST HDL_TAP TRUE
J 0
(-2075 5300);
DISPLAY 0.872340 (-2075 5300);
DISPLAY INVISIBLE (-2075 5300);
FORCEPROP 1 LAST PATH I34
J 0
(-2402 5425);
DISPLAY 0.872340 (-2402 5425);
PAINT GREEN (-2402 5425);
DISPLAY INVISIBLE (-2402 5425);
FORCEADD TAP..1
(-2200 5325);
FORCEPROP 3 LASTPIN (-2250 5325) SIG_NAME P5E_CPU0_P1_RX_BUF_DN<7>
J 0
(-2240 5335);
DISPLAY 0.659574 (-2240 5335);
PAINT MONO (-2240 5335);
DISPLAY INVISIBLE (-2240 5335);
FORCEPROP 1 LASTPIN (-2250 5325) BN 7
J 0
(-2262 5333);
DISPLAY 0.680851 (-2262 5333);
PAINT GREEN (-2262 5333);
FORCEPROP 2 LAST CDS_LIB standard
J 0
(-2200 5325);
DISPLAY INVISIBLE (-2200 5325);
FORCEPROP 1 LAST BODY_TYPE PLUMBING
J 0
(-2200 5375);
DISPLAY 0.872340 (-2200 5375);
PAINT GREEN (-2200 5375);
DISPLAY INVISIBLE (-2200 5375);
FORCEPROP 1 LAST HDL_TAP TRUE
J 0
(-1875 5200);
DISPLAY 0.872340 (-1875 5200);
DISPLAY INVISIBLE (-1875 5200);
FORCEPROP 1 LAST PATH I35
J 0
(-2202 5325);
DISPLAY 0.872340 (-2202 5325);
PAINT GREEN (-2202 5325);
DISPLAY INVISIBLE (-2202 5325);
FORCEADD OFFPAGE..1
R 2
(-1175 5450);
FORCEPROP 2 LAST $XR0 118 
J 0
(-989 5450);
DISPLAY 0.638298 (-989 5450);
PAINT MONO (-989 5450);
FORCEPROP 2 LAST CDS_LIB standard
J 0
(-1175 5450);
DISPLAY INVISIBLE (-1175 5450);
FORCEPROP 1 LAST OFFPAGE TRUE
J 2
(-1500 5325);
DISPLAY 0.872340 (-1500 5325);
DISPLAY INVISIBLE (-1500 5325);
FORCEPROP 1 LAST COMMENT_BODY TRUE
J 2
(-1300 5350);
DISPLAY 0.872340 (-1300 5350);
PAINT GREEN (-1300 5350);
DISPLAY INVISIBLE (-1300 5350);
FORCEPROP 2 LAST PATH I36
J 0
(-1000 5525);
DISPLAY 0.680851 (-1000 5525);
DISPLAY INVISIBLE (-1000 5525);
FORCEADD OFFPAGE..1
R 2
(-1175 5525);
FORCEPROP 2 LAST $XR0 118 
J 0
(-989 5525);
DISPLAY 0.638298 (-989 5525);
PAINT MONO (-989 5525);
FORCEPROP 2 LAST CDS_LIB standard
J 0
(-1175 5525);
DISPLAY INVISIBLE (-1175 5525);
FORCEPROP 1 LAST OFFPAGE TRUE
J 2
(-1500 5400);
DISPLAY 0.872340 (-1500 5400);
DISPLAY INVISIBLE (-1500 5400);
FORCEPROP 1 LAST COMMENT_BODY TRUE
J 2
(-1300 5425);
DISPLAY 0.872340 (-1300 5425);
PAINT GREEN (-1300 5425);
DISPLAY INVISIBLE (-1300 5425);
FORCEPROP 2 LAST PATH I37
J 0
(-1000 5600);
DISPLAY 0.680851 (-1000 5600);
DISPLAY INVISIBLE (-1000 5600);
FORCEADD PT5161LRS..2
(-3425 4175);
FORCEPROP 1 LAST LOCATION U6011
J 0
(-3775 5800);
DISPLAY 0.723404 (-3775 5800);
PAINT GREEN (-3775 5800);
FORCEPROP 0 LAST $SEC 2
J 0
(-3775 5950);
DISPLAY 0.680851 (-3775 5950);
PAINT MONO (-3775 5950);
DISPLAY INVISIBLE (-3775 5950);
FORCEPROP 0 LAST CDS_SEC 2
J 0
(-3775 5950);
DISPLAY 0.680851 (-3775 5950);
DISPLAY INVISIBLE (-3775 5950);
FORCEPROP 0 LASTPIN (-2975 5325) $PN CJ2
J 0
(-2965 5335);
DISPLAY 0.680851 (-2965 5335);
PAINT MONO (-2965 5335);
FORCEPROP 0 LASTPIN (-2975 4975) $PN CT2
J 0
(-2965 4985);
DISPLAY 0.680851 (-2965 4985);
PAINT MONO (-2965 4985);
FORCEPROP 0 LASTPIN (-2975 4625) $PN DC2
J 0
(-2965 4635);
DISPLAY 0.680851 (-2965 4635);
PAINT MONO (-2965 4635);
FORCEPROP 0 LASTPIN (-2975 4275) $PN DK2
J 0
(-2965 4285);
DISPLAY 0.680851 (-2965 4285);
PAINT MONO (-2965 4285);
FORCEPROP 0 LASTPIN (-2975 3925) $PN DU2
J 0
(-2965 3935);
DISPLAY 0.680851 (-2965 3935);
PAINT MONO (-2965 3935);
FORCEPROP 0 LASTPIN (-2975 3575) $PN ED2
J 0
(-2965 3585);
DISPLAY 0.680851 (-2965 3585);
PAINT MONO (-2965 3585);
FORCEPROP 0 LASTPIN (-2975 3225) $PN EL2
J 0
(-2965 3235);
DISPLAY 0.680851 (-2965 3235);
PAINT MONO (-2965 3235);
FORCEPROP 0 LASTPIN (-2975 2875) $PN EV2
J 0
(-2965 2885);
DISPLAY 0.680851 (-2965 2885);
PAINT MONO (-2965 2885);
FORCEPROP 0 LASTPIN (-2975 5425) $PN CL1
J 0
(-2965 5435);
DISPLAY 0.680851 (-2965 5435);
PAINT MONO (-2965 5435);
FORCEPROP 0 LASTPIN (-2975 5075) $PN CV1
J 0
(-2965 5085);
DISPLAY 0.680851 (-2965 5085);
PAINT MONO (-2965 5085);
FORCEPROP 0 LASTPIN (-2975 4725) $PN DE1
J 0
(-2965 4735);
DISPLAY 0.680851 (-2965 4735);
PAINT MONO (-2965 4735);
FORCEPROP 0 LASTPIN (-2975 4375) $PN DM1
J 0
(-2965 4385);
DISPLAY 0.680851 (-2965 4385);
PAINT MONO (-2965 4385);
FORCEPROP 0 LASTPIN (-2975 4025) $PN DW1
J 0
(-2965 4035);
DISPLAY 0.680851 (-2965 4035);
PAINT MONO (-2965 4035);
FORCEPROP 0 LASTPIN (-2975 3675) $PN EF1
J 0
(-2965 3685);
DISPLAY 0.680851 (-2965 3685);
PAINT MONO (-2965 3685);
FORCEPROP 0 LASTPIN (-2975 3325) $PN EN1
J 0
(-2965 3335);
DISPLAY 0.680851 (-2965 3335);
PAINT MONO (-2965 3335);
FORCEPROP 0 LASTPIN (-2975 2975) $PN EY1
J 0
(-2965 2985);
DISPLAY 0.680851 (-2965 2985);
PAINT MONO (-2965 2985);
FORCEPROP 2 LAST PART_TYPE SMLF
J 0
(-3775 5900);
DISPLAY 0.680851 (-3775 5900);
FORCEPROP 1 LAST MATERIAL IC
J 0
(-3775 5650);
DISPLAY 0.723404 (-3775 5650);
PAINT GREEN (-3775 5650);
FORCEPROP 2 LAST VALUE PT5161LRS
J 0
(-3775 5850);
DISPLAY 0.680851 (-3775 5850);
FORCEPROP 2 LAST CDS_LIB pure_quanta
J 0
(-3425 4175);
DISPLAY INVISIBLE (-3425 4175);
FORCEPROP 1 LAST CDS_LMAN_SYM_OUTLINE -350,1450,300,-1400
J 0
(-3425 4175);
DISPLAY 0.468085 (-3425 4175);
PAINT GREEN (-3425 4175);
DISPLAY INVISIBLE (-3425 4175);
FORCEPROP 1 LAST NEEDS_NO_SIZE TRUE
J 0
(-3425 4175);
DISPLAY 0.723404 (-3425 4175);
PAINT GREEN (-3425 4175);
DISPLAY INVISIBLE (-3425 4175);
FORCEPROP 1 LAST PATH I38
J 0
(-3425 4175);
DISPLAY 0.723404 (-3425 4175);
PAINT GREEN (-3425 4175);
DISPLAY INVISIBLE (-3425 4175);
FORCEPROP 1 LAST PART_NUMBER AJ051610U03
J 0
(-3775 5725);
DISPLAY 0.723404 (-3775 5725);
PAINT GREEN (-3775 5725);
DISPLAY INVISIBLE (-3775 5725);
FORCEADD TAP..1
(-6850 3300);
FORCEPROP 3 LASTPIN (-6900 3300) SIG_NAME P5E_CPU0_P1_RX_BUF_DP<9>
J 0
(-6890 3310);
DISPLAY 0.659574 (-6890 3310);
PAINT MONO (-6890 3310);
DISPLAY INVISIBLE (-6890 3310);
FORCEPROP 1 LASTPIN (-6900 3300) BN 9
J 0
(-6912 3308);
DISPLAY 0.680851 (-6912 3308);
PAINT GREEN (-6912 3308);
FORCEPROP 2 LAST CDS_LIB standard
J 0
(-6850 3300);
DISPLAY INVISIBLE (-6850 3300);
FORCEPROP 1 LAST BODY_TYPE PLUMBING
J 0
(-6850 3350);
DISPLAY 0.872340 (-6850 3350);
PAINT GREEN (-6850 3350);
DISPLAY INVISIBLE (-6850 3350);
FORCEPROP 1 LAST HDL_TAP TRUE
J 0
(-6525 3175);
DISPLAY 0.872340 (-6525 3175);
DISPLAY INVISIBLE (-6525 3175);
FORCEPROP 1 LAST PATH I4
J 0
(-6852 3300);
DISPLAY 0.872340 (-6852 3300);
PAINT GREEN (-6852 3300);
DISPLAY INVISIBLE (-6852 3300);
FORCEADD TAP..1
(-6650 3200);
FORCEPROP 3 LASTPIN (-6700 3200) SIG_NAME P5E_CPU0_P1_RX_BUF_DN<9>
J 0
(-6690 3210);
DISPLAY 0.659574 (-6690 3210);
PAINT MONO (-6690 3210);
DISPLAY INVISIBLE (-6690 3210);
FORCEPROP 1 LASTPIN (-6700 3200) BN 9
J 0
(-6712 3208);
DISPLAY 0.680851 (-6712 3208);
PAINT GREEN (-6712 3208);
FORCEPROP 2 LAST CDS_LIB standard
J 0
(-6650 3200);
DISPLAY INVISIBLE (-6650 3200);
FORCEPROP 1 LAST BODY_TYPE PLUMBING
J 0
(-6650 3250);
DISPLAY 0.872340 (-6650 3250);
PAINT GREEN (-6650 3250);
DISPLAY INVISIBLE (-6650 3250);
FORCEPROP 1 LAST HDL_TAP TRUE
J 0
(-6325 3075);
DISPLAY 0.872340 (-6325 3075);
DISPLAY INVISIBLE (-6325 3075);
FORCEPROP 1 LAST PATH I5
J 0
(-6652 3200);
DISPLAY 0.872340 (-6652 3200);
PAINT GREEN (-6652 3200);
DISPLAY INVISIBLE (-6652 3200);
FORCEADD TAP..1
(-6850 3650);
FORCEPROP 3 LASTPIN (-6900 3650) SIG_NAME P5E_CPU0_P1_RX_BUF_DP<10>
J 0
(-6890 3660);
DISPLAY 0.659574 (-6890 3660);
PAINT MONO (-6890 3660);
DISPLAY INVISIBLE (-6890 3660);
FORCEPROP 1 LASTPIN (-6900 3650) BN 10
J 0
(-6912 3658);
DISPLAY 0.680851 (-6912 3658);
PAINT GREEN (-6912 3658);
FORCEPROP 2 LAST CDS_LIB standard
J 0
(-6850 3650);
DISPLAY INVISIBLE (-6850 3650);
FORCEPROP 1 LAST BODY_TYPE PLUMBING
J 0
(-6850 3700);
DISPLAY 0.872340 (-6850 3700);
PAINT GREEN (-6850 3700);
DISPLAY INVISIBLE (-6850 3700);
FORCEPROP 1 LAST HDL_TAP TRUE
J 0
(-6525 3525);
DISPLAY 0.872340 (-6525 3525);
DISPLAY INVISIBLE (-6525 3525);
FORCEPROP 1 LAST PATH I6
J 0
(-6852 3650);
DISPLAY 0.872340 (-6852 3650);
PAINT GREEN (-6852 3650);
DISPLAY INVISIBLE (-6852 3650);
FORCEADD TAP..1
(-6650 3550);
FORCEPROP 3 LASTPIN (-6700 3550) SIG_NAME P5E_CPU0_P1_RX_BUF_DN<10>
J 0
(-6690 3560);
DISPLAY 0.659574 (-6690 3560);
PAINT MONO (-6690 3560);
DISPLAY INVISIBLE (-6690 3560);
FORCEPROP 1 LASTPIN (-6700 3550) BN 10
J 0
(-6712 3558);
DISPLAY 0.680851 (-6712 3558);
PAINT GREEN (-6712 3558);
FORCEPROP 2 LAST CDS_LIB standard
J 0
(-6650 3550);
DISPLAY INVISIBLE (-6650 3550);
FORCEPROP 1 LAST BODY_TYPE PLUMBING
J 0
(-6650 3600);
DISPLAY 0.872340 (-6650 3600);
PAINT GREEN (-6650 3600);
DISPLAY INVISIBLE (-6650 3600);
FORCEPROP 1 LAST HDL_TAP TRUE
J 0
(-6325 3425);
DISPLAY 0.872340 (-6325 3425);
DISPLAY INVISIBLE (-6325 3425);
FORCEPROP 1 LAST PATH I7
J 0
(-6652 3550);
DISPLAY 0.872340 (-6652 3550);
PAINT GREEN (-6652 3550);
DISPLAY INVISIBLE (-6652 3550);
FORCEADD TAP..1
(-6650 3900);
FORCEPROP 3 LASTPIN (-6700 3900) SIG_NAME P5E_CPU0_P1_RX_BUF_DN<11>
J 0
(-6690 3910);
DISPLAY 0.659574 (-6690 3910);
PAINT MONO (-6690 3910);
DISPLAY INVISIBLE (-6690 3910);
FORCEPROP 1 LASTPIN (-6700 3900) BN 11
J 0
(-6712 3908);
DISPLAY 0.680851 (-6712 3908);
PAINT GREEN (-6712 3908);
FORCEPROP 2 LAST CDS_LIB standard
J 0
(-6650 3900);
DISPLAY INVISIBLE (-6650 3900);
FORCEPROP 1 LAST BODY_TYPE PLUMBING
J 0
(-6650 3950);
DISPLAY 0.872340 (-6650 3950);
PAINT GREEN (-6650 3950);
DISPLAY INVISIBLE (-6650 3950);
FORCEPROP 1 LAST HDL_TAP TRUE
J 0
(-6325 3775);
DISPLAY 0.872340 (-6325 3775);
DISPLAY INVISIBLE (-6325 3775);
FORCEPROP 1 LAST PATH I8
J 0
(-6652 3900);
DISPLAY 0.872340 (-6652 3900);
PAINT GREEN (-6652 3900);
DISPLAY INVISIBLE (-6652 3900);
FORCEADD TAP..1
(-6850 4000);
FORCEPROP 3 LASTPIN (-6900 4000) SIG_NAME P5E_CPU0_P1_RX_BUF_DP<11>
J 0
(-6890 4010);
DISPLAY 0.659574 (-6890 4010);
PAINT MONO (-6890 4010);
DISPLAY INVISIBLE (-6890 4010);
FORCEPROP 1 LASTPIN (-6900 4000) BN 11
J 0
(-6912 4008);
DISPLAY 0.680851 (-6912 4008);
PAINT GREEN (-6912 4008);
FORCEPROP 2 LAST CDS_LIB standard
J 0
(-6850 4000);
DISPLAY INVISIBLE (-6850 4000);
FORCEPROP 1 LAST BODY_TYPE PLUMBING
J 0
(-6850 4050);
DISPLAY 0.872340 (-6850 4050);
PAINT GREEN (-6850 4050);
DISPLAY INVISIBLE (-6850 4050);
FORCEPROP 1 LAST HDL_TAP TRUE
J 0
(-6525 3875);
DISPLAY 0.872340 (-6525 3875);
DISPLAY INVISIBLE (-6525 3875);
FORCEPROP 1 LAST PATH I9
J 0
(-6852 4000);
DISPLAY 0.872340 (-6852 4000);
PAINT GREEN (-6852 4000);
DISPLAY INVISIBLE (-6852 4000);
FORCEADD QUANTA_TITLE_BLOCK_C..1
(0 0);
FORCEPROP 0 LAST CDS_CON_LAST_MODIFIED Thu Sep 14 16:12:52 2023
J 0
(-1885 15);
DISPLAY INVISIBLE (-1885 15);
FORCEPROP 1 LAST CUSTOM_TXT_CDS <CON_LAST_MODIFIED>
J 0
(-1885 15);
DISPLAY 0.978723 (-1885 15);
FORCEPROP 2 LAST CUSTOM_TXT_CDS <XR_PAGE_TITLE>
J 0
(-7890 5250);
DISPLAY 0.638298 (-7890 5250);
PAINT PINK (-7890 5250);
DISPLAY INVISIBLE (-7890 5250);
FORCEPROP 1 LAST CUSTOM_TXT_CDS <NAME_2>
J 0
(-3175 50);
FORCEPROP 1 LAST CUSTOM_TXT_CDS <NAME_1>
J 0
(-3175 175);
FORCEPROP 1 LAST CUSTOM_TXT_CDS <Q_NUMBER>
J 0
(-1403 103);
DISPLAY 1.212766 (-1403 103);
FORCEPROP 1 LAST CUSTOM_TXT_CDS <Q_PROJ>
J 0
(-2382 102);
DISPLAY 1.212766 (-2382 102);
FORCEPROP 1 LAST CUSTOM_TXT_CDS <Q_REV>
J 0
(-184 103);
DISPLAY 1.212766 (-184 103);
FORCEPROP 1 LAST CUSTOM_TXT_CDS <CON_PAGE_NUM> OF <CON_TOTAL_PAGES>
J 0
(-446 18);
DISPLAY 0.978723 (-446 18);
FORCEPROP 1 LAST Q_TITLE RETIMER_CPU0_P1(3)
J 0
(-9366 26);
DISPLAY 2.446809 (-9366 26);
PAINT GREEN (-9366 26);
FORCEPROP 2 LAST CDS_LIB pure_quanta
J 0
(0 0);
DISPLAY INVISIBLE (0 0);
FORCEPROP 1 LAST CDS_LMAN_SYM_OUTLINE -9475,6775,100,-125
J 0
(0 0);
DISPLAY 0.468085 (0 0);
PAINT GREEN (0 0);
DISPLAY INVISIBLE (0 0);
FORCEPROP 2 LAST PAGE_BORDER TRUE
J 0
(-7890 5250);
DISPLAY 0.638298 (-7890 5250);
PAINT PINK (-7890 5250);
DISPLAY INVISIBLE (-7890 5250);
FORCEPROP 2 LAST CDS_XR_PAGE_TITLE CR-286 : @T6G_MB_LIB.T6G(SCH_1):PAGE286
J 0
(-7890 5250);
DISPLAY 0.638298 (-7890 5250);
PAINT PINK (-7890 5250);
DISPLAY INVISIBLE (-7890 5250);
FORCEPROP 1 LAST Q_DEPT BU9
J 1
(-3763 49);
DISPLAY 1.957447 (-3763 49);
PAINT GREEN (-3763 49);
DISPLAY INVISIBLE (-3763 49);
FORCEPROP 1 LAST COMMENT_BODY TRUE
J 0
(12 -13);
DISPLAY 0.978723 (12 -13);
PAINT GREEN (12 -13);
DISPLAY INVISIBLE (12 -13);
WIRE 17 -1 (-6800 5500)(-6800 5425);
WIRE 17 -1 (-6800 5500)(-5675 5500);
FORCEPROP 2 LAST SIG_NAME P5E_CPU0_P1_RX_BUF_DP<15:8>
J 0
(-6535 5510);
DISPLAY 0.680851 (-6535 5510);
PAINT WHITE (-6535 5510);
WIRE 17 -1 (-2150 3950)(-2150 4300);
WIRE 17 -1 (-2150 3950)(-2150 3600);
WIRE 17 -1 (-2150 4650)(-2150 4300);
WIRE 17 -1 (-2150 5000)(-2150 4650);
WIRE 17 -1 (-2150 3600)(-2150 3250);
WIRE 17 -1 (-2150 3250)(-2150 2900);
WIRE 17 -1 (-2150 5350)(-2150 5000);
WIRE 17 -1 (-2150 5450)(-2150 5350);
WIRE 17 -1 (-2150 5450)(-1225 5450);
FORCEPROP 2 LAST SIG_NAME P5E_CPU0_P1_RX_BUF_DN<7:0>
J 0
(-2085 5460);
DISPLAY 0.680851 (-2085 5460);
PAINT WHITE (-2085 5460);
WIRE 17 -1 (-2350 4050)(-2350 3700);
WIRE 17 -1 (-2350 4050)(-2350 4400);
WIRE 17 -1 (-2350 3700)(-2350 3350);
WIRE 17 -1 (-2350 3350)(-2350 3000);
WIRE 17 -1 (-2350 4750)(-2350 4400);
WIRE 17 -1 (-2350 5100)(-2350 4750);
WIRE 17 -1 (-2350 5450)(-2350 5100);
WIRE 17 -1 (-2350 5525)(-2350 5450);
WIRE 17 -1 (-2350 5525)(-1225 5525);
FORCEPROP 2 LAST SIG_NAME P5E_CPU0_P1_RX_BUF_DP<7:0>
J 0
(-2085 5535);
DISPLAY 0.680851 (-2085 5535);
PAINT WHITE (-2085 5535);
WIRE 17 -1 (-6800 5075)(-6800 4725);
WIRE 17 -1 (-6800 5425)(-6800 5075);
WIRE 17 -1 (-6800 4725)(-6800 4375);
WIRE 17 -1 (-6800 4025)(-6800 4375);
WIRE 17 -1 (-6600 4975)(-6600 4625);
WIRE 17 -1 (-6600 5325)(-6600 4975);
WIRE 17 -1 (-6600 4625)(-6600 4275);
WIRE 17 -1 (-6600 3925)(-6600 4275);
WIRE 17 -1 (-6600 5425)(-6600 5325);
WIRE 17 -1 (-6600 5425)(-5675 5425);
FORCEPROP 2 LAST SIG_NAME P5E_CPU0_P1_RX_BUF_DN<15:8>
J 0
(-6535 5435);
DISPLAY 0.680851 (-6535 5435);
PAINT WHITE (-6535 5435);
WIRE 17 -1 (-6800 4025)(-6800 3675);
WIRE 17 -1 (-6800 3675)(-6800 3325);
WIRE 17 -1 (-6800 3325)(-6800 2975);
WIRE 17 -1 (-6600 3925)(-6600 3575);
WIRE 17 -1 (-6600 3575)(-6600 3225);
WIRE 17 -1 (-6600 3225)(-6600 2875);
WIRE 16 -1 (-2975 4625)(-2250 4625);
WIRE 16 -1 (-2975 4725)(-2450 4725);
WIRE 16 -1 (-2975 4275)(-2250 4275);
WIRE 16 -1 (-2975 5075)(-2450 5075);
WIRE 16 -1 (-2975 4375)(-2450 4375);
WIRE 16 -1 (-2975 3325)(-2450 3325);
WIRE 16 -1 (-7425 4000)(-6900 4000);
WIRE 16 -1 (-7425 3650)(-6900 3650);
WIRE 16 -1 (-7425 5050)(-6900 5050);
WIRE 16 -1 (-7425 2850)(-6700 2850);
WIRE 16 -1 (-7425 4250)(-6700 4250);
WIRE 16 -1 (-7425 4950)(-6700 4950);
WIRE 16 -1 (-7425 5300)(-6700 5300);
WIRE 16 -1 (-7425 2950)(-6900 2950);
WIRE 16 -1 (-7425 3200)(-6700 3200);
WIRE 16 -1 (-7425 3300)(-6900 3300);
WIRE 16 -1 (-7425 3550)(-6700 3550);
WIRE 16 -1 (-7425 3900)(-6700 3900);
WIRE 16 -1 (-7425 4350)(-6900 4350);
WIRE 16 -1 (-7425 4600)(-6700 4600);
WIRE 16 -1 (-7425 4700)(-6900 4700);
WIRE 16 -1 (-2975 2975)(-2450 2975);
WIRE 16 -1 (-2975 4975)(-2250 4975);
WIRE 16 -1 (-2975 2875)(-2250 2875);
WIRE 16 -1 (-2975 3225)(-2250 3225);
WIRE 16 -1 (-2975 5325)(-2250 5325);
WIRE 16 -1 (-2975 5425)(-2450 5425);
WIRE 16 -1 (-2975 4025)(-2450 4025);
WIRE 16 -1 (-2975 3575)(-2250 3575);
WIRE 16 -1 (-2975 3675)(-2450 3675);
WIRE 16 -1 (-2975 3925)(-2250 3925);
WIRE 16 -1 (-7425 5400)(-6900 5400);
FORCENOTE
EXAMAX TO RETIMER
(-3700 2000) 0;
DISPLAY LEFT (-3700 2000);
DISPLAY 3.148936 (-3700 2000);
FORCENOTE
EXAMAX TO RETIMER
(-8250 2025) 0;
DISPLAY LEFT (-8250 2025);
DISPLAY 3.148936 (-8250 2025);
FORCENOTE
P5E_CPU0_P1_RX_BUF_DP/DN<0-15>
(-9050 6325) 0;
DISPLAY LEFT (-9050 6325);
DISPLAY 2.000000 (-9050 6325);
QUIT
